# T6G (Grand Teton) — schematic netlist excerpt (pin names and nets, part order shuffled) for the footprints in the layout excerpt that follows; sources: Cadence DE-HDL packaged netlist, KiCad conversion of 04192023_DAF0TMB3IC0_F0TG_MB_C_brd_V02_OCP.brd

PC243  Q_CAP  0.1UF 25V 10% X7R  pkg 0402  page 210 : A = PVDDCR_CPU0_P1_VMON ; B = GND
C371  Q_CAP  4.7UF 6.3V 20% X6S  pkg 0402  page 345 : A = P1V8_CPU1_RT2_1A ; B = GND
R977  Q_RES  0 5% CHIP  pkg 0201LF  page 276 : A = SMB_RT_CPU0_P0_R_SDA ; B = SMB_RT_CPU0_P0_R2_SDA

(kicad_pcb
	(version 20260206)
	(generator "pcbnew")
	(generator_version "10.0")
	(general
		(thickness 1.6)
		(legacy_teardrops no)
	)
	(paper "A4")
	(title_block
		(title "04192023_DAF0TMB3IC0_F0TG_MB_C_brd_V02_OCP.brd")
		(comment 1 "Grand Teton / footprints 6341-6343 of 8354")
	)
	(layers
		(0 "F.Cu" signal "TOP")
		(4 "In1.Cu" signal "GND")
		(6 "In2.Cu" signal "IN1")
		(8 "In3.Cu" signal "GND1")
		(10 "In4.Cu" signal "IN2")
		(12 "In5.Cu" signal "GND2")
		(14 "In6.Cu" signal "IN3")
		(16 "In7.Cu" signal "GND3")
		(18 "In8.Cu" signal "VCC")
		(20 "In9.Cu" signal "VCC1")
		(22 "In10.Cu" signal "GND4")
		(24 "In11.Cu" signal "IN4")
		(26 "In12.Cu" signal "GND5")
		(28 "In13.Cu" signal "IN5")
		(30 "In14.Cu" signal "GND6")
		(32 "In15.Cu" signal "IN6")
		(34 "In16.Cu" signal "GND7")
		(2 "B.Cu" signal "BOTTOM")
		(9 "F.Adhes" user "F.Adhesive")
		(11 "B.Adhes" user "B.Adhesive")
		(13 "F.Paste" user "Package Geometry/Pastemask Top")
		(15 "B.Paste" user "Package Geometry/Pastemask Bottom")
		(5 "F.SilkS" user "Ref Des/Silkscreen Top")
		(7 "B.SilkS" user "Ref Des/Silkscreen Bottom")
		(1 "F.Mask" user "Board Geometry/Soldermask Top")
		(3 "B.Mask" user "Board Geometry/Soldermask Bottom")
		(17 "Dwgs.User" user "User.Drawings")
		(19 "Cmts.User" user "User.Comments")
		(21 "Eco1.User" user "User.Eco1")
		(23 "Eco2.User" user "User.Eco2")
		(25 "Edge.Cuts" user "Board Geometry/Outline")
		(27 "Margin" user)
		(31 "F.CrtYd" user "Package Geometry/Place Bound Top")
		(29 "B.CrtYd" user "Package Geometry/Place Bound Bottom")
		(35 "F.Fab" user "Ref Des/Assembly Top")
		(33 "B.Fab" user "Ref Des/Assembly Bottom")
	)
	(footprint ""
		(layer "B.Cu")
		(at 233.172 -341.884 180)
		(property "Reference" "R977"
			(at 0 0 0)
			(layer "B.SilkS")
			(hide yes)
			(effects
				(font
					(size 1.27 1.27)
				)
				(justify mirror)
			)
		)
		(property "Value" ""
			(at 0 0 0)
			(layer "B.Fab")
			(effects
				(font
					(size 1.27 1.27)
				)
				(justify mirror)
			)
		)
		(duplicate_pad_numbers_are_jumpers no)
		(fp_line
			(start 0.32512 0.175006)
			(end 0.32512 -0.175006)
			(stroke
				(width 0.1)
				(type default)
			)
			(layer "B.Fab")
		)
		(fp_line
			(start 0.32512 -0.175006)
			(end -0.32512 -0.175006)
			(stroke
				(width 0.1)
				(type default)
			)
			(layer "B.Fab")
		)
		(fp_line
			(start -0.32512 0.175006)
			(end 0.32512 0.175006)
			(stroke
				(width 0.1)
				(type default)
			)
			(layer "B.Fab")
		)
		(fp_line
			(start -0.32512 -0.175006)
			(end -0.32512 0.175006)
			(stroke
				(width 0.1)
				(type default)
			)
			(layer "B.Fab")
		)
		(pad "1" smd rect
			(at 0.2667 0)
			(size 0.3048 0.381)
			(layers "B.Cu" "B.Mask" "B.Paste")
			(net "SMB_RT_CPU0_P0_R_SDA")
		)
		(pad "2" smd rect
			(at -0.2667 0 180)
			(size 0.3048 0.381)
			(layers "B.Cu" "B.Mask" "B.Paste")
			(net "SMB_RT_CPU0_P0_R2_SDA")
		)
	)
	(footprint ""
		(layer "B.Cu")
		(at 155.419044 -390.560052 90)
		(property "Reference" "C371"
			(at 0 0 90)
			(layer "B.SilkS")
			(hide yes)
			(effects
				(font
					(size 1.27 1.27)
				)
				(justify mirror)
			)
		)
		(property "Value" ""
			(at 0 0 90)
			(layer "B.Fab")
			(effects
				(font
					(size 1.27 1.27)
				)
				(justify mirror)
			)
		)
		(duplicate_pad_numbers_are_jumpers no)
		(fp_line
			(start 0.7874 -0.4064)
			(end -0.7874 -0.4064)
			(stroke
				(width 0.1524)
				(type default)
			)
			(layer "B.SilkS")
		)
		(fp_line
			(start -0.7874 -0.4064)
			(end -0.7874 0.4064)
			(stroke
				(width 0.1524)
				(type default)
			)
			(layer "B.SilkS")
		)
		(fp_line
			(start 0.7874 0.4064)
			(end 0.7874 -0.4064)
			(stroke
				(width 0.1524)
				(type default)
			)
			(layer "B.SilkS")
		)
		(fp_line
			(start -0.7874 0.4064)
			(end 0.7874 0.4064)
			(stroke
				(width 0.1524)
				(type default)
			)
			(layer "B.SilkS")
		)
		(fp_line
			(start 0.67945 -0.305054)
			(end 0.12065 -0.305054)
			(stroke
				(width 0.1)
				(type default)
			)
			(layer "B.Fab")
		)
		(fp_line
			(start 0.12065 -0.305054)
			(end 0.12065 -0.2794)
			(stroke
				(width 0.1)
				(type default)
			)
			(layer "B.Fab")
		)
		(fp_line
			(start -0.12065 -0.3048)
			(end -0.67945 -0.3048)
			(stroke
				(width 0.1)
				(type default)
			)
			(layer "B.Fab")
		)
		(fp_line
			(start -0.67945 -0.3048)
			(end -0.67945 0.3048)
			(stroke
				(width 0.1)
				(type default)
			)
			(layer "B.Fab")
		)
		(fp_line
			(start 0.12065 -0.2794)
			(end -0.12065 -0.2794)
			(stroke
				(width 0.1)
				(type default)
			)
			(layer "B.Fab")
		)
		(fp_line
			(start -0.12065 -0.2794)
			(end -0.12065 -0.3048)
			(stroke
				(width 0.1)
				(type default)
			)
			(layer "B.Fab")
		)
		(fp_line
			(start 0.12065 0.2794)
			(end 0.12065 0.3048)
			(stroke
				(width 0.1)
				(type default)
			)
			(layer "B.Fab")
		)
		(fp_line
			(start -0.120396 0.2794)
			(end 0.12065 0.2794)
			(stroke
				(width 0.1)
				(type default)
			)
			(layer "B.Fab")
		)
		(fp_line
			(start 0.67945 0.3048)
			(end 0.67945 -0.305054)
			(stroke
				(width 0.1)
				(type default)
			)
			(layer "B.Fab")
		)
		(fp_line
			(start 0.12065 0.3048)
			(end 0.67945 0.3048)
			(stroke
				(width 0.1)
				(type default)
			)
			(layer "B.Fab")
		)
		(fp_line
			(start -0.120396 0.3048)
			(end -0.120396 0.2794)
			(stroke
				(width 0.1)
				(type default)
			)
			(layer "B.Fab")
		)
		(fp_line
			(start -0.67945 0.3048)
			(end -0.120396 0.3048)
			(stroke
				(width 0.1)
				(type default)
			)
			(layer "B.Fab")
		)
		(pad "1" smd circle
			(at 0.40005 0 270)
			(size 0 0)
			(layers "B.Cu" "B.Mask" "B.Paste")
			(net "P1V8_CPU1_RT2_1A")
		)
		(pad "2" smd circle
			(at -0.40005 0 270)
			(size 0 0)
			(layers "B.Cu" "B.Mask" "B.Paste")
			(net "GND")
		)
	)
	(footprint ""
		(layer "B.Cu")
		(at 101.385878 -142.59941 180)
		(property "Reference" "PC243"
			(at 0 0 0)
			(layer "B.SilkS")
			(hide yes)
			(effects
				(font
					(size 1.27 1.27)
				)
				(justify mirror)
			)
		)
		(property "Value" ""
			(at 0 0 0)
			(layer "B.Fab")
			(effects
				(font
					(size 1.27 1.27)
				)
				(justify mirror)
			)
		)
		(duplicate_pad_numbers_are_jumpers no)
		(fp_line
			(start 0.7874 0.4064)
			(end 0.7874 -0.4064)
			(stroke
				(width 0.1524)
				(type default)
			)
			(layer "B.SilkS")
		)
		(fp_line
			(start 0.7874 -0.4064)
			(end -0.7874 -0.4064)
			(stroke
				(width 0.1524)
				(type default)
			)
			(layer "B.SilkS")
		)
		(fp_line
			(start -0.7874 0.4064)
			(end 0.7874 0.4064)
			(stroke
				(width 0.1524)
				(type default)
			)
			(layer "B.SilkS")
		)
		(fp_line
			(start -0.7874 -0.4064)
			(end -0.7874 0.4064)
			(stroke
				(width 0.1524)
				(type default)
			)
			(layer "B.SilkS")
		)
		(fp_line
			(start 0.67945 0.3048)
			(end 0.67945 -0.305054)
			(stroke
				(width 0.1)
				(type default)
			)
			(layer "B.Fab")
		)
		(fp_line
			(start 0.67945 -0.305054)
			(end 0.12065 -0.305054)
			(stroke
				(width 0.1)
				(type default)
			)
			(layer "B.Fab")
		)
		(fp_line
			(start 0.12065 0.3048)
			(end 0.67945 0.3048)
			(stroke
				(width 0.1)
				(type default)
			)
			(layer "B.Fab")
		)
		(fp_line
			(start 0.12065 0.2794)
			(end 0.12065 0.3048)
			(stroke
				(width 0.1)
				(type default)
			)
			(layer "B.Fab")
		)
		(fp_line
			(start 0.12065 -0.2794)
			(end -0.12065 -0.2794)
			(stroke
				(width 0.1)
				(type default)
			)
			(layer "B.Fab")
		)
		(fp_line
			(start 0.12065 -0.305054)
			(end 0.12065 -0.2794)
			(stroke
				(width 0.1)
				(type default)
			)
			(layer "B.Fab")
		)
		(fp_line
			(start -0.120396 0.3048)
			(end -0.120396 0.2794)
			(stroke
				(width 0.1)
				(type default)
			)
			(layer "B.Fab")
		)
		(fp_line
			(start -0.120396 0.2794)
			(end 0.12065 0.2794)
			(stroke
				(width 0.1)
				(type default)
			)
			(layer "B.Fab")
		)
		(fp_line
			(start -0.12065 -0.2794)
			(end -0.12065 -0.3048)
			(stroke
				(width 0.1)
				(type default)
			)
			(layer "B.Fab")
		)
		(fp_line
			(start -0.12065 -0.3048)
			(end -0.67945 -0.3048)
			(stroke
				(width 0.1)
				(type default)
			)
			(layer "B.Fab")
		)
		(fp_line
			(start -0.67945 0.3048)
			(end -0.120396 0.3048)
			(stroke
				(width 0.1)
				(type default)
			)
			(layer "B.Fab")
		)
		(fp_line
			(start -0.67945 -0.3048)
			(end -0.67945 0.3048)
			(stroke
				(width 0.1)
				(type default)
			)
			(layer "B.Fab")
		)
		(pad "1" smd circle
			(at 0.40005 0)
			(size 0 0)
			(layers "B.Cu" "B.Mask" "B.Paste")
			(net "PVDDCR_CPU0_P1_VMON")
		)
		(pad "2" smd circle
			(at -0.40005 0)
			(size 0 0)
			(layers "B.Cu" "B.Mask" "B.Paste")
			(net "GND")
		)
	)
)
